# T6G (Grand Teton) — schematic parts with pin connectivity, parts 5488–5635 of 8303; source: Cadence DE-HDL packaged netlist (pstxprt.dat, pstxnet.dat, pstchip.dat)

R764  Q_RES  84.5K 1% CHIP  pkg 0402LF  page 91 : 1 = PD_CHF_CPU0_DIMM_SAA ; 2 = GND
R765  Q_RES  15.4K 1% CHIP  pkg 0402LF  page 93 : 1 = PD_CHH_CPU0_DIMM_SAA ; 2 = GND
R766  Q_RES  23.2K 1% CHIP  pkg 0402LF  page 94 : 1 = PD_CHI_CPU0_DIMM_SAA ; 2 = GND
R767  Q_RES  35.7K 1% CHIP  pkg 0402LF  page 95 : 1 = PD_CHJ_CPU0_DIMM_SAA ; 2 = GND
R768  Q_RES  54.9K 1% CHIP  pkg 0402LF  page 96 : 1 = PD_CHK_CPU0_DIMM_SAA ; 2 = GND
R769  Q_RES  84.5K 1% CHIP  pkg 0402LF  page 97 : 1 = PD_CHL_CPU0_DIMM_SAA ; 2 = GND
R770  Q_RES  15.4K 1% CHIP  pkg 0402LF  page 99 : 1 = PD_CHB_CPU1_DIMM_SAA ; 2 = GND
R771  Q_RES  23.2K 1% CHIP  pkg 0402LF  page 100 : 1 = PD_CHC_CPU1_DIMM_SAA ; 2 = GND
R772  Q_RES  35.7K 1% CHIP  pkg 0402LF  page 101 : 1 = PD_CHD_CPU1_DIMM_SAA ; 2 = GND
R773  Q_RES  84.5K 1% CHIP  pkg 0402LF  page 103 : 1 = PD_CHF_CPU1_DIMM_SAA ; 2 = GND
R774  Q_RES  15.4K 1% CHIP  pkg 0402LF  page 105 : 1 = PD_CHH_CPU1_DIMM_SAA ; 2 = GND
R775  Q_RES  23.2K 1% CHIP  pkg 0402LF  page 106 : 1 = PD_CHI_CPU1_DIMM_SAA ; 2 = GND
R776  Q_RES  35.7K 1% CHIP  pkg 0402LF  page 107 : 1 = PD_CHJ_CPU1_DIMM_SAA ; 2 = GND
R777  Q_RES  54.9K 1% CHIP  pkg 0402LF  page 108 : 1 = PD_CHK_CPU1_DIMM_SAA ; 2 = GND
R778  Q_RES  84.5K 1% CHIP  pkg 0402LF  page 109 : 1 = PD_CHL_CPU1_DIMM_SAA ; 2 = GND
R779  Q_RES  0 5% CHIP  pkg 0201LF  page 331 : 1 = SMB_RT_CPU1_P1_R_SCL ; 2 = SMB_RT_CPU1_P1_R2_SCL
R780  Q_RES  0 5% CHIP  pkg 0201LF  page 331 : 1 = SMB_RT_CPU1_P1_R_SDA ; 2 = SMB_RT_CPU1_P1_R2_SDA
R781  Q_RES  4.7K 5% EMPTY  pkg 0201LF  page 331 : 1 = P1V8_CPU1_RT_1D ; 2 = GPIO2_RT_CPU1_P1
R782  Q_RES  10K 1% CHIP  pkg 0201LF  page 331 : 1 = GPIO2_RT_CPU1_P1 ; 2 = GND
R783  Q_RES  10K 1% CHIP  pkg 0201LF  page 331 : 1 = GPIO3_RT_CPU1_P1 ; 2 = GND
R784  Q_RES  4.7K 5% EMPTY  pkg 0201LF  page 331 : 1 = P1V8_CPU1_RT_1D ; 2 = TEST0_RT_CPU1_P1
R785  Q_RES  4.7K 5% CHIP  pkg 0201LF  page 331 : 1 = TEST0_RT_CPU1_P1 ; 2 = GND
R786  Q_RES  4.7K 5% EMPTY  pkg 0201LF  page 331 : 1 = P1V8_CPU1_RT_1D ; 2 = TEST1_RT_CPU1_P1
R787  Q_RES  4.7K 5% CHIP  pkg 0201LF  page 331 : 1 = TEST1_RT_CPU1_P1 ; 2 = GND
R788  Q_RES  4.7K 5% EMPTY  pkg 0201LF  page 331 : 1 = P1V8_CPU1_RT_1D ; 2 = TEST2_RT_CPU1_P1
R789  Q_RES  0 5% EMPTY  pkg 0402LF  page 160 : 1 = SMB_CPU0_CPU1_APML_BUF1_SCL ; 2 = SMB_CPU0_CPU1_APML_BUF1_SCL_R1
R790  Q_RES  0 5% EMPTY  pkg 0402LF  page 160 : 1 = SMB_CPU0_CPU1_APML_BUF1_SDA ; 2 = SMB_CPU0_CPU1_APML_BUF1_SDA_R1
R791  Q_RES  4.7K 5% CHIP  pkg 0201LF  page 331 : 1 = TEST2_RT_CPU1_P1 ; 2 = GND
R792  Q_RES  4.7K 5% CHIP  pkg 0201LF  page 331 : 1 = JTAG_TEST_MODE_RT_CPU1_P1 ; 2 = GND
R793  Q_RES  4.7K 5% CHIP  pkg 0201LF  page 331 : 1 = P1V8_CPU1_RT_1D ; 2 = MODE_RT_CPU1_P1
R794  Q_RES  4.7K 5% EMPTY  pkg 0201LF  page 331 : 1 = MODE_RT_CPU1_P1 ; 2 = GND
R795  Q_RES  1K 1% EMPTY  pkg 0201LF  page 331 : 1 = P1V8_CPU1_RT_1D ; 2 = RT_CPU1_P1_ADDR1
R796  Q_RES  1K 1% CHIP  pkg 0201LF  page 331 : 1 = RT_CPU1_P1_ADDR1 ; 2 = GND
R797  Q_RES  0 5% CHIP  pkg 0201LF  page 185 : 1 = SMB_RT_CPU0_P0_ROM_MUX_2D_R_SDA ; 2 = SMB_RT_CPU0_P0_ROM_MUX_2D_SDA
R798  Q_RES  33 5% CHIP  pkg 0402LF  page 81 : 1 = RST_PERST_M2_0_R_N ; 2 = RST_PERST_M2_0_N
R799  Q_RES  0 5% CHIP  pkg 0201LF  page 185 : 1 = SMB_RT_CPU0_P0_ROM_MUX_2D_R_SCL ; 2 = SMB_RT_CPU0_P0_ROM_MUX_2D_SCL
R800  Q_RES  10K 1% CHIP  pkg 0402LF  page 83 : 1 = RST_PERST_E1S_0_N ; 2 = GND
R801  Q_RES  0 5% CHIP  pkg 0201LF  page 185 : 1 = SMB_RT_CPU1_P0_ROM_MUX_2D_SDA ; 2 = SMB_RT_CPU1_P0_ROM_MUX_2D_R_SDA
R802  Q_RES  0 5% CHIP  pkg 0201LF  page 185 : 1 = SMB_RT_CPU1_P0_ROM_MUX_2D_SCL ; 2 = SMB_RT_CPU1_P0_ROM_MUX_2D_R_SCL
R803  Q_RES  0 5% CHIP  pkg 0201LF  page 185 : 1 = SMB_RT_CPU1_P1_ROM_MUX_2D_SDA ; 2 = SMB_RT_CPU1_P1_ROM_MUX_2D_R_SDA
R804  Q_RES  10K 1% CHIP  pkg 0402LF  page 83 : 1 = RST_PERST_M2_0_N ; 2 = GND
R805  Q_RES  0 5% CHIP  pkg 0201LF  page 185 : 1 = SMB_RT_CPU1_P1_ROM_MUX_2D_SCL ; 2 = SMB_RT_CPU1_P1_ROM_MUX_2D_R_SCL
R806  Q_RES  0 5% CHIP  pkg 0201LF  page 185 : 1 = SMB_RT_CPU1_P3_ROM_MUX_2D_SDA ; 2 = SMB_RT_CPU1_P3_ROM_MUX_2D_R_SDA
R807  Q_RES  0 5% CHIP  pkg 0201LF  page 185 : 1 = SMB_RT_CPU1_P3_ROM_MUX_2D_SCL ; 2 = SMB_RT_CPU1_P3_ROM_MUX_2D_R_SCL
R808  Q_RES  0 5% CHIP  pkg 0201LF  page 185 : 1 = SMB_RT_CPU1_P2_ROM_MUX_2D_SDA ; 2 = SMB_RT_CPU1_P2_ROM_MUX_2D_R_SDA
R809  Q_RES  0 5% CHIP  pkg 0201LF  page 185 : 1 = SMB_RT_CPU1_P2_ROM_MUX_2D_SCL ; 2 = SMB_RT_CPU1_P2_ROM_MUX_2D_R_SCL
R810  Q_RES  1K 1% CHIP  pkg 0201LF  page 185 : 1 = P1V8_CPU1_RT_1D ; 2 = SMB_RT_CPU1_P3_ROM_R_SDA
R811  Q_RES  1K 1% CHIP  pkg 0402LF  page 77 : 1 = PVDD18_S5_P0 ; 2 = SPI_CPU0_CS0_N
R812  Q_RES  1K 1% CHIP  pkg 0201LF  page 185 : 1 = P1V8_CPU1_RT_1D ; 2 = SMB_RT_CPU1_P3_ROM_R_SCL
R813  Q_RES  10K 5% CHIP  pkg 0402LF  page 164 : 1 = PVDD18_S5_P0 ; 2 = UART_CPU0_UART0_RX
R814  Q_RES  10K 5% EMPTY  pkg 0402LF  page 164 : 1 = PVDD18_S5_P0 ; 2 = UART_CPU0_UART0_TX
R815  Q_RES  10K 5% EMPTY  pkg 0402LF  page 164 : 1 = PVDD18_S5_P0 ; 2 = UART_CPU0_SCM_UART1_TX
R816  Q_RES  10K 5% CHIP  pkg 0402LF  page 164 : 1 = PVDD18_S5_P0 ; 2 = UART_CPU0_SCM_UART1_RX
R817  Q_RES  0 5% CHIP  pkg 0402LF  page 164 : 1 = UART_CPU0_UART0_RX ; 2 = UART_CPU0_UART0_R_RX
R818  Q_RES  0 5% CHIP  pkg 0402LF  page 164 : 1 = UART_CPU0_LVC3_UART0_R_TX ; 2 = UART_CPU0_LVC3_UART0_TX
R819  Q_RES  0 5% CHIP  pkg 0402LF  page 164 : 1 = UART_CPU0_LVC3_UART0_R_RX ; 2 = UART_CPU0_LVC3_UART0_RX
R820  Q_RES  10K 5% EMPTY  pkg 0402LF  page 164 : 1 = UART_VCC_J13 ; 2 = P5V_AUX
R821  Q_RES  10K 5% CHIP  pkg 0402LF  page 164 : 1 = P3V3_AUX ; 2 = UART_VCC_J13
R822  Q_RES  10K 5% CHIP  pkg 0402LF  page 164 : 1 = P3V3_AUX ; 2 = UART_CPU0_SCM_LVC3_UART1_TX
R823  Q_RES  10K 5% EMPTY  pkg 0402LF  page 164 : 1 = P3V3_AUX ; 2 = UART_CPU0_SCM_LVC3_UART1_R_RX
R824  Q_RES  10K 5% CHIP  pkg 0402LF  page 164 : 1 = P3V3_AUX ; 2 = UART_CPU0_LVC3_UART0_TX
R825  Q_RES  10K 5% EMPTY  pkg 0402LF  page 164 : 1 = P3V3_AUX ; 2 = UART_CPU0_LVC3_UART0_RX
R826  Q_RES  1K 1% CHIP  pkg 0201LF  page 185 : 1 = P1V8_CPU1_RT_1D ; 2 = SMB_RT_CPU1_P2_ROM_R_SDA
R827  Q_RES  1K 1% CHIP  pkg 0201LF  page 185 : 1 = P1V8_CPU1_RT_1D ; 2 = SMB_RT_CPU1_P2_ROM_R_SCL
R828  Q_RES  0 5% CHIP  pkg 0201LF  page 185 : 1 = SMB_RT_CPU0_P1_ROM_MUX_2D_R_SDA ; 2 = SMB_RT_CPU0_P1_ROM_MUX_2D_SDA
R829  Q_RES  0 5% CHIP  pkg 0201LF  page 185 : 1 = SMB_RT_CPU0_P1_ROM_MUX_2D_R_SCL ; 2 = SMB_RT_CPU0_P1_ROM_MUX_2D_SCL
R830  Q_RES  0 5% CHIP  pkg 0201LF  page 185 : 1 = SMB_RT_CPU0_P3_ROM_MUX_2D_R_SDA ; 2 = SMB_RT_CPU0_P3_ROM_MUX_2D_SDA
R831  Q_RES  0 5% CHIP  pkg 0201LF  page 185 : 1 = SMB_RT_CPU0_P3_ROM_MUX_2D_R_SCL ; 2 = SMB_RT_CPU0_P3_ROM_MUX_2D_SCL
R832  Q_RES  0 5% CHIP  pkg 0201LF  page 185 : 1 = SMB_RT_CPU0_P2_ROM_MUX_2D_R_SDA ; 2 = SMB_RT_CPU0_P2_ROM_MUX_2D_SDA
R833  Q_RES  0 5% CHIP  pkg 0201LF  page 185 : 1 = SMB_RT_CPU0_P2_ROM_MUX_2D_R_SCL ; 2 = SMB_RT_CPU0_P2_ROM_MUX_2D_SCL
R834  Q_RES  1K 1% CHIP  pkg 0201LF  page 185 : 1 = P1V8_CPU0_RT_1D ; 2 = SMB_RT_CPU0_P0_ROM_R_SDA
R835  Q_RES  1K 1% CHIP  pkg 0201LF  page 185 : 1 = P1V8_CPU0_RT_1D ; 2 = SMB_RT_CPU0_P0_ROM_R_SCL
R836  Q_RES  1K 1% CHIP  pkg 0201LF  page 185 : 1 = P1V8_CPU0_RT_1D ; 2 = SMB_RT_CPU0_P1_ROM_R_SDA
R837  Q_RES  1K 1% CHIP  pkg 0201LF  page 185 : 1 = P1V8_CPU0_RT_1D ; 2 = SMB_RT_CPU0_P1_ROM_R_SCL
R838  Q_RES  1K 1% CHIP  pkg 0201LF  page 185 : 1 = P1V8_CPU0_RT_1D ; 2 = SMB_RT_CPU0_P3_ROM_R_SDA
R839  Q_RES  1K 1% CHIP  pkg 0201LF  page 185 : 1 = P1V8_CPU0_RT_1D ; 2 = SMB_RT_CPU0_P3_ROM_R_SCL
R840  Q_RES  1K 1% CHIP  pkg 0201LF  page 185 : 1 = P1V8_CPU0_RT_1D ; 2 = SMB_RT_CPU0_P2_ROM_R_SDA
R841  Q_RES  1K 1% CHIP  pkg 0201LF  page 185 : 1 = P1V8_CPU0_RT_1D ; 2 = SMB_RT_CPU0_P2_ROM_R_SCL
R842  Q_RES  4.7K 5% EMPTY  pkg 0201LF  page 185 : 1 = P1V8_AUX ; 2 = RT_ROM_SMB_MUX_ADDR2
R843  Q_RES  4.7K 5% EMPTY  pkg 0201LF  page 185 : 1 = P1V8_AUX ; 2 = RT_ROM_SMB_MUX_ADDR1
R844  Q_RES  4.7K 5% EMPTY  pkg 0201LF  page 185 : 1 = P1V8_AUX ; 2 = RT_ROM_SMB_MUX_ADDR0
R845  Q_RES  4.7K 5% CHIP  pkg 0201LF  page 185 : 1 = RT_ROM_SMB_MUX_ADDR2 ; 2 = GND
R846  Q_RES  4.7K 5% CHIP  pkg 0201LF  page 185 : 1 = RT_ROM_SMB_MUX_ADDR1 ; 2 = GND
R847  Q_RES  4.7K 5% CHIP  pkg 0201LF  page 185 : 1 = RT_ROM_SMB_MUX_ADDR0 ; 2 = GND
R848  Q_RES  0 5% CHIP  pkg 0201LF  page 185 : 1 = RST_SMB_RT_ROM_R1_N ; 2 = RST_SMB_RT_ROM_N
R849  Q_RES  10K 1% CHIP  pkg 0201LF  page 185 : 1 = RST_SMB_RT_ROM_R1_N ; 2 = GND
R850  Q_RES  0 5% CHIP  pkg 0201LF  page 185 : 1 = SMB_MUX_RT_ROM_SDA ; 2 = SMB_MUX_RT_ROM_R1_SDA
R851  Q_RES  0 5% CHIP  pkg 0201LF  page 185 : 1 = SMB_MUX_RT_ROM_SCL ; 2 = SMB_MUX_RT_ROM_R1_SCL
R852  Q_RES  0 5% EMPTY  pkg 0402LF  page 345 : 1 = P1V8_CPU1_RT2_1A_1D ; 2 = P1V8_CPU1_RT2_1A
R853  Q_RES  0 5% EMPTY  pkg 0402LF  page 345 : 1 = P1V8_CPU1_RT2_1A_1D ; 2 = P1V8_CPU1_RT2_1A
R854  Q_RES  0 5% CHIP  pkg 0201LF  page 342 : 1 = RST_RT_CPU1_P2_PERST_N ; 2 = RST_RT_CPU1_P2_PERST_R_N
R855  Q_RES  11.5K 1% EMPTY  pkg 0402LF  page 169 : 1 = P12V_AUX_DSC_VOL ; 2 = GND
R856  Q_RES  0 5% CHIP  pkg 0402LF  page 81 : 1 = FM_HDT_HDR_RESET_N ; 2 = HDT_HDR_RESET_N
R857  Q_RES  0 5% EMPTY  pkg 0402LF  page 345 : 1 = P1V8_CPU1_RT_1D ; 2 = P1V8_CPU1_RT2_1A_1D
R858  Q_RES  0 5% EMPTY  pkg 0603LF  page 345 : 1 = P0V9_CPU1_RT_2D ; 2 = P0V9_CPU1_RT2_2A_2D
R859  Q_RES  0 5% CHIP  pkg 0603LF  page 345 : 1 = P0V9_CPU1_RT2_2A_2D ; 2 = P0V9_CPU1_RT2_2A
R860  Q_RES  0 5% CHIP  pkg 0201LF  page 342 : 1 = RST_RT_CPU1_P2_RESET_N ; 2 = RST_RT_CPU1_P2_RESET_R_N
R861  Q_RES  1K 1% CHIP  pkg 0201LF  page 342 : 1 = P1V8_CPU1_RT_1D ; 2 = RT_CPU1_P2_ADDR3
R862  Q_RES  0 5% CHIP  pkg 0402LF  page 54 : 1 = CPU1_XTRIG_R2_L6 ; 2 = CPU1_XTRIG_L6
R863  Q_RES  1K 1% EMPTY  pkg 0201LF  page 342 : 1 = RT_CPU1_P2_ADDR3 ; 2 = GND
R864  Q_RES  1K 1% EMPTY  pkg 0201LF  page 342 : 1 = P1V8_CPU1_RT_1D ; 2 = RT_CPU1_P2_ADDR2
R865  Q_RES  20K 1% CHIP  pkg 0201LF  page 342 : 1 = RT_CPU1_P2_ADDR2 ; 2 = GND
R866  Q_RES  10K 1% CHIP  pkg 0201LF  page 342 : 1 = RST_RT_CPU1_P2_PERST_R_N ; 2 = GND
R867  Q_RES  10K 1% CHIP  pkg 0201LF  page 342 : 1 = RST_RT_CPU1_P2_RESET_R_N ; 2 = GND
R868  Q_RES  4.7K 5% EMPTY  pkg 0201LF  page 342 : 1 = P1V8_CPU1_RT_1D ; 2 = RT_CPU1_P2_SCAN_MODE
R869  Q_RES  200 1% CHIP  pkg 0201LF  page 342 : 1 = RT_CPU1_P2_SCAN_MODE ; 2 = GND
R870  Q_RES  4.7K 5% EMPTY  pkg 0201LF  page 342 : 1 = P1V8_CPU1_RT_1D ; 2 = RST_RT_CPU1_P2_RESET_R_N
R871  Q_RES  4.7K 5% EMPTY  pkg 0201LF  page 342 : 1 = P1V8_CPU1_RT_1D ; 2 = JTAG_TEST_MODE_RT_CPU1_P2
R872  Q_RES  0 5% CHIP  pkg 0201LF  page 342 : 1 = SMB_RT_CPU1_P2_R_SCL ; 2 = SMB_RT_CPU1_P2_R2_SCL
R873  Q_RES  0 5% CHIP  pkg 0201LF  page 342 : 1 = SMB_RT_CPU1_P2_R_SDA ; 2 = SMB_RT_CPU1_P2_R2_SDA
R874  Q_RES  4.7K 5% EMPTY  pkg 0201LF  page 342 : 1 = P1V8_CPU1_RT_1D ; 2 = GPIO2_RT_CPU1_P2
R875  Q_RES  10K 1% CHIP  pkg 0201LF  page 342 : 1 = GPIO2_RT_CPU1_P2 ; 2 = GND
R876  Q_RES  10K 1% CHIP  pkg 0201LF  page 342 : 1 = GPIO3_RT_CPU1_P2 ; 2 = GND
R877  Q_RES  0 5% CHIP  pkg 0402LF  page 133 : 1 = RST_PERST_OCP_SFF_BUF2_N ; 2 = RST_PERST0_OCP_SFF_N
R878  Q_RES  4.7K 5% EMPTY  pkg 0201LF  page 342 : 1 = P1V8_CPU1_RT_1D ; 2 = TEST0_RT_CPU1_P2
R879  Q_RES  4.7K 5% CHIP  pkg 0201LF  page 342 : 1 = TEST0_RT_CPU1_P2 ; 2 = GND
R880  Q_RES  4.7K 5% EMPTY  pkg 0201LF  page 342 : 1 = P1V8_CPU1_RT_1D ; 2 = TEST1_RT_CPU1_P2
R881  Q_RES  4.7K 5% CHIP  pkg 0201LF  page 342 : 1 = TEST1_RT_CPU1_P2 ; 2 = GND
R882  Q_RES  4.7K 5% EMPTY  pkg 0201LF  page 342 : 1 = P1V8_CPU1_RT_1D ; 2 = TEST2_RT_CPU1_P2
R883  Q_RES  4.7K 5% CHIP  pkg 0201LF  page 342 : 1 = TEST2_RT_CPU1_P2 ; 2 = GND
R884  Q_RES  4.7K 5% CHIP  pkg 0201LF  page 342 : 1 = JTAG_TEST_MODE_RT_CPU1_P2 ; 2 = GND
R885  Q_RES  4.7K 5% CHIP  pkg 0201LF  page 342 : 1 = P1V8_CPU1_RT_1D ; 2 = MODE_RT_CPU1_P2
R886  Q_RES  4.7K 5% EMPTY  pkg 0201LF  page 342 : 1 = MODE_RT_CPU1_P2 ; 2 = GND
R887  Q_RES  1K 1% EMPTY  pkg 0201LF  page 342 : 1 = P1V8_CPU1_RT_1D ; 2 = RT_CPU1_P2_ADDR1
R888  Q_RES  10K 5% EMPTY  pkg 0402LF  page 151 : 1 = P3V3_AUX ; 2 = SCM_SPARE_0
R889  Q_RES  10K 5% EMPTY  pkg 0402LF  page 151 : 1 = SCM_SPARE_0 ; 2 = GND
R890  Q_RES  10K 5% EMPTY  pkg 0402LF  page 151 : 1 = P3V3_AUX ; 2 = SCM_SPARE_1
R891  Q_RES  10K 5% EMPTY  pkg 0402LF  page 151 : 1 = SCM_SPARE_1 ; 2 = GND
R892  Q_RES  1K 1% CHIP  pkg 0201LF  page 342 : 1 = RT_CPU1_P2_ADDR1 ; 2 = GND
R893  Q_RES  0 5% EMPTY  pkg 0402LF  page 356 : 1 = P1V8_CPU1_RT3_1A_1D ; 2 = P1V8_CPU1_RT3_1A
R894  Q_RES  0 5% EMPTY  pkg 0402LF  page 356 : 1 = P1V8_CPU1_RT3_1A_1D ; 2 = P1V8_CPU1_RT3_1A
R895  Q_RES  0 5% CHIP  pkg 0201LF  page 353 : 1 = RST_RT_CPU1_P3_PERST_N ; 2 = RST_RT_CPU1_P3_PERST_R_N
R896  Q_RES  30K 1% EMPTY  pkg 0402LF  page 169 : 1 = P12V_AUX ; 2 = P3V3_AUX_DSC_VOL
R897  Q_RES  0 5% EMPTY  pkg 0402LF  page 356 : 1 = P1V8_CPU1_RT_1D ; 2 = P1V8_CPU1_RT3_1A_1D
R898  Q_RES  0 5% EMPTY  pkg 0603LF  page 356 : 1 = P0V9_CPU1_RT_2D ; 2 = P0V9_CPU1_RT3_2A_2D
R899  Q_RES  0 5% CHIP  pkg 0402LF  page 133 : 1 = RST_PERST_OCP_SFF_BUF2_N ; 2 = RST_PERST1_OCP_SFF_N
R900  Q_RES  0 5% CHIP  pkg 0603LF  page 356 : 1 = P0V9_CPU1_RT3_2A_2D ; 2 = P0V9_CPU1_RT3_2A
R901  Q_RES  0 5% CHIP  pkg 0201LF  page 353 : 1 = RST_RT_CPU1_P3_RESET_N ; 2 = RST_RT_CPU1_P3_RESET_R_N
R902  Q_RES  1K 1% CHIP  pkg 0201LF  page 353 : 1 = P1V8_CPU1_RT_1D ; 2 = RT_CPU1_P3_ADDR3
R903  Q_RES  1K 1% EMPTY  pkg 0201LF  page 353 : 1 = RT_CPU1_P3_ADDR3 ; 2 = GND
R904  Q_RES  1K 1% EMPTY  pkg 0201LF  page 353 : 1 = P1V8_CPU1_RT_1D ; 2 = RT_CPU1_P3_ADDR2
R905  Q_RES  0 5% CHIP  pkg 0402LF  page 133 : 1 = RST_PERST_OCP_SFF_BUF2_N ; 2 = RST_PERST2_OCP_SFF_N
R906  Q_RES  20K 1% CHIP  pkg 0201LF  page 353 : 1 = RT_CPU1_P3_ADDR2 ; 2 = GND
R907  Q_RES  10K 1% CHIP  pkg 0201LF  page 353 : 1 = RST_RT_CPU1_P3_PERST_R_N ; 2 = GND
R908  Q_RES  10K 1% CHIP  pkg 0201LF  page 353 : 1 = RST_RT_CPU1_P3_RESET_R_N ; 2 = GND
R909  Q_RES  4.7K 5% EMPTY  pkg 0201LF  page 353 : 1 = P1V8_CPU1_RT_1D ; 2 = RT_CPU1_P3_SCAN_MODE
R910  Q_RES  200 1% CHIP  pkg 0201LF  page 353 : 1 = RT_CPU1_P3_SCAN_MODE ; 2 = GND
R911  Q_RES  4.7K 5% EMPTY  pkg 0201LF  page 353 : 1 = P1V8_CPU1_RT_1D ; 2 = RST_RT_CPU1_P3_RESET_R_N
